(kicad_pcb
	(version 20241229)
	(generator "pcbnew")
	(generator_version "9.0")
	(general
		(thickness 1.711)
		(legacy_teardrops no)
	)
	(paper "A4")
	(title_block
		(title "Antmicro Baseboard for Jetson AGX Thor")
		(date "2026-02-18")
		(rev "1.1.0")
		(company "Antmicro Ltd")
		(comment 1 "www.antmicro.com")
		(comment 9 "footprints 264-266 of 1170")
	)
	(layers
		(0 "F.Cu" signal)
		(4 "In1.Cu" signal)
		(6 "In2.Cu" signal)
		(8 "In3.Cu" signal)
		(10 "In4.Cu" jumper)
		(12 "In5.Cu" signal)
		(14 "In6.Cu" signal)
		(16 "In7.Cu" signal)
		(18 "In8.Cu" signal)
		(2 "B.Cu" signal)
		(9 "F.Adhes" user "F.Adhesive")
		(11 "B.Adhes" user "B.Adhesive")
		(13 "F.Paste" user)
		(15 "B.Paste" user)
		(5 "F.SilkS" user "F.Silkscreen")
		(7 "B.SilkS" user "B.Silkscreen")
		(1 "F.Mask" user)
		(3 "B.Mask" user)
		(17 "Dwgs.User" user "User.Drawings")
		(19 "Cmts.User" user "User.Comments")
		(21 "Eco1.User" user "User.Eco1")
		(23 "Eco2.User" user "User.Eco2")
		(25 "Edge.Cuts" user)
		(27 "Margin" user)
		(31 "F.CrtYd" user "F.Courtyard")
		(29 "B.CrtYd" user "B.Courtyard")
		(35 "F.Fab" user)
		(33 "B.Fab" user)
	)
	(footprint "antmicro-footprints:R_0402_1005Metric"
		(layer "F.Cu")
		(at 179.009468 66.03 90)
		(descr "Resistor SMD 0402")
		(tags "resistor SMD 0402")
		(property "Reference" "R23"
			(at 0.89 0.45 90)
			(layer "F.SilkS")
			(effects
				(font
					(size 0.7 0.7)
					(thickness 0.15)
				)
				(justify left bottom)
			)
		)
		(property "Value" "R_499k_0402"
			(at -1.011843 1.772047 90)
			(layer "F.Fab")
			(effects
				(font
					(size 0.7 0.7)
					(thickness 0.15)
				)
				(justify left bottom)
			)
		)
		(property "Datasheet" "https://www.mouser.com/datasheet/2/54/cr-1858361.pdf"
			(at 0 0 90)
			(layer "F.Fab")
			(hide yes)
			(effects
				(font
					(size 1.27 1.27)
					(thickness 0.15)
				)
			)
		)
		(property "Description" "SMD Chip Resistor, 499 kohm, ± 1%, 63 mW, 0402 [1005 Metric], Thick Film, General Purpose"
			(at 0 0 90)
			(layer "F.Fab")
			(hide yes)
			(effects
				(font
					(size 1.27 1.27)
					(thickness 0.15)
				)
			)
		)
		(property "MPN" "CR0402-FX-4993GLF"
			(at 0 0 90)
			(unlocked yes)
			(layer "F.Fab")
			(hide yes)
			(effects
				(font
					(size 1 1)
					(thickness 0.15)
				)
			)
		)
		(property "Manufacturer" "Bourns"
			(at 0 0 90)
			(unlocked yes)
			(layer "F.Fab")
			(hide yes)
			(effects
				(font
					(size 1 1)
					(thickness 0.15)
				)
			)
		)
		(property "License" "Apache-2.0"
			(at 0 0 90)
			(unlocked yes)
			(layer "F.Fab")
			(hide yes)
			(effects
				(font
					(size 1 1)
					(thickness 0.15)
				)
			)
		)
		(property "Author" "Antmicro"
			(at 0 0 90)
			(unlocked yes)
			(layer "F.Fab")
			(hide yes)
			(effects
				(font
					(size 1 1)
					(thickness 0.15)
				)
			)
		)
		(property "Val" "499k"
			(at 0 0 90)
			(unlocked yes)
			(layer "F.Fab")
			(hide yes)
			(effects
				(font
					(size 1 1)
					(thickness 0.15)
				)
			)
		)
		(property "Tolerance" "1%"
			(at 0 0 90)
			(unlocked yes)
			(layer "F.Fab")
			(hide yes)
			(effects
				(font
					(size 1 1)
					(thickness 0.15)
				)
			)
		)
		(component_classes
			(class "DCDC_20V")
		)
		(sheetname "/DCDC/")
		(sheetfile "dcdc.kicad_sch")
		(attr smd exclude_from_pos_files exclude_from_bom dnp)
		(fp_rect
			(start -0.925 -0.47)
			(end 0.925 0.47)
			(stroke
				(width 0.05)
				(type default)
			)
			(fill no)
			(layer "F.CrtYd")
		)
		(fp_rect
			(start -0.5 -0.25)
			(end 0.5 0.25)
			(stroke
				(width 0.15)
				(type solid)
			)
			(fill no)
			(layer "F.Fab")
		)
		(fp_text user "Author: Antmicro"
			(at -0.95 4.169 90)
			(layer "F.Fab")
			(effects
				(font
					(size 0.7 0.7)
					(thickness 0.15)
				)
				(justify left bottom)
			)
		)
		(fp_text user "License: Apache-2.0"
			(at -0.95 5.169 90)
			(layer "F.Fab")
			(effects
				(font
					(size 0.7 0.7)
					(thickness 0.15)
				)
				(justify left bottom)
			)
		)
		(fp_text user "${REFERENCE}"
			(at -0.95 3.168 90)
			(layer "F.Fab")
			(effects
				(font
					(size 0.7 0.7)
					(thickness 0.15)
				)
				(justify left bottom)
			)
		)
		(pad "1" smd roundrect
			(at -0.48 0 90)
			(size 0.59 0.64)
			(layers "F.Cu" "F.Mask" "F.Paste")
			(roundrect_rratio 0.25)
			(net 1208 "/DCDC/20V_MODE1")
			(pintype "passive")
		)
		(pad "2" smd roundrect
			(at 0.48 0 90)
			(size 0.59 0.64)
			(layers "F.Cu" "F.Mask" "F.Paste")
			(roundrect_rratio 0.25)
			(net 905 "/DCDC/20V_VDD")
			(pintype "passive")
		)
	)
	(footprint "antmicro-footprints:C_0805_2012Metric"
		(layer "F.Cu")
		(at 165.88 93.31 -90)
		(descr "Capacitor SMD 0805")
		(tags "capacitor SMD 0805")
		(property "Reference" "C294"
			(at 1.745 0.425 90)
			(layer "F.SilkS")
			(effects
				(font
					(size 0.7 0.7)
					(thickness 0.15)
				)
				(justify right top)
			)
		)
		(property "Value" "C_22u_25V_0805"
			(at -2.055717 1.963152 90)
			(layer "F.Fab")
			(effects
				(font
					(size 0.7 0.7)
					(thickness 0.15)
				)
				(justify right top)
			)
		)
		(property "Datasheet" "https://product.samsungsem.com/mlcc/CL21A226MAYNNN.do"
			(at 0 0 90)
			(layer "F.Fab")
			(hide yes)
			(effects
				(font
					(size 1.27 1.27)
					(thickness 0.15)
				)
			)
		)
		(property "Description" "SMT Multilayer Ceramic Capacitor, 22uF, +/-20%, 25V, X5R, 0805 [2012 Metric]"
			(at 0 0 90)
			(layer "F.Fab")
			(hide yes)
			(effects
				(font
					(size 1.27 1.27)
					(thickness 0.15)
				)
			)
		)
		(property "MPN" "CL21A226MAYNNNE"
			(at 0 0 270)
			(unlocked yes)
			(layer "F.Fab")
			(hide yes)
			(effects
				(font
					(size 1 1)
					(thickness 0.15)
				)
			)
		)
		(property "Manufacturer" "Samsung Electro-Mechanics"
			(at 0 0 270)
			(unlocked yes)
			(layer "F.Fab")
			(hide yes)
			(effects
				(font
					(size 1 1)
					(thickness 0.15)
				)
			)
		)
		(property "License" "Apache-2.0"
			(at 0 0 270)
			(unlocked yes)
			(layer "F.Fab")
			(hide yes)
			(effects
				(font
					(size 1 1)
					(thickness 0.15)
				)
			)
		)
		(property "Author" "Antmicro"
			(at 0 0 270)
			(unlocked yes)
			(layer "F.Fab")
			(hide yes)
			(effects
				(font
					(size 1 1)
					(thickness 0.15)
				)
			)
		)
		(property "Val" "22u"
			(at 0 0 270)
			(unlocked yes)
			(layer "F.Fab")
			(hide yes)
			(effects
				(font
					(size 1 1)
					(thickness 0.15)
				)
			)
		)
		(property "Voltage" "25V"
			(at 0 0 270)
			(unlocked yes)
			(layer "F.Fab")
			(hide yes)
			(effects
				(font
					(size 1 1)
					(thickness 0.15)
				)
			)
		)
		(property "Dielectric" "X5R"
			(at 0 0 270)
			(unlocked yes)
			(layer "F.Fab")
			(hide yes)
			(effects
				(font
					(size 1 1)
					(thickness 0.15)
				)
			)
		)
		(property "Public" "False"
			(at 0 0 270)
			(unlocked yes)
			(layer "F.Fab")
			(hide yes)
			(effects
				(font
					(size 1 1)
					(thickness 0.15)
				)
			)
		)
		(component_classes
			(class "DCDC_SOM")
		)
		(sheetname "/DCDC/")
		(sheetfile "dcdc.kicad_sch")
		(attr smd)
		(fp_line
			(start -0.3 0.7)
			(end 0.3 0.7)
			(stroke
				(width 0.15)
				(type solid)
			)
			(layer "F.SilkS")
		)
		(fp_line
			(start -0.3 -0.7)
			(end 0.3 -0.7)
			(stroke
				(width 0.15)
				(type solid)
			)
			(layer "F.SilkS")
		)
		(fp_rect
			(start 1.95 -0.9)
			(end -1.95 0.9)
			(stroke
				(width 0.05)
				(type default)
			)
			(fill no)
			(layer "F.CrtYd")
		)
		(fp_rect
			(start -0.95 -0.675)
			(end 0.95 0.675)
			(stroke
				(width 0.15)
				(type solid)
			)
			(fill no)
			(layer "F.Fab")
		)
		(fp_text user "${REFERENCE}"
			(at -1.9 3.947 90)
			(layer "F.Fab")
			(effects
				(font
					(size 0.7 0.7)
					(thickness 0.15)
				)
				(justify right top)
			)
		)
		(fp_text user "Author: Antmicro"
			(at -1.9 5.947 90)
			(layer "F.Fab")
			(effects
				(font
					(size 0.7 0.7)
					(thickness 0.15)
				)
				(justify right top)
			)
		)
		(fp_text user "License: Apache-2.0"
			(at -1.9 4.947 90)
			(layer "F.Fab")
			(effects
				(font
					(size 0.7 0.7)
					(thickness 0.15)
				)
				(justify right top)
			)
		)
		(pad "1" smd roundrect
			(at -1.1 0 270)
			(size 1.2 1.3)
			(layers "F.Cu" "F.Mask" "F.Paste")
			(roundrect_rratio 0.25)
			(net 1 "GND")
			(pintype "passive")
		)
		(pad "2" smd roundrect
			(at 1.1 0 270)
			(size 1.2 1.3)
			(layers "F.Cu" "F.Mask" "F.Paste")
			(roundrect_rratio 0.25)
			(net 903 "/DCDC/16V_OUT")
			(pintype "passive")
		)
	)
	(footprint "antmicro-footprints:C_0402_1005Metric"
		(layer "F.Cu")
		(at 152.48 121.5 180)
		(descr "Capacitor SMD 0402")
		(tags "capacitor SMD 0402")
		(property "Reference" "C2"
			(at -2.42 0.3 0)
			(layer "F.SilkS")
			(effects
				(font
					(size 0.7 0.7)
					(thickness 0.15)
				)
				(justify right top)
			)
		)
		(property "Value" "C_100n_0402"
			(at -1.022927 2.155213 0)
			(layer "F.Fab")
			(effects
				(font
					(size 0.7 0.7)
					(thickness 0.15)
				)
				(justify right top)
			)
		)
		(property "Datasheet" "https://www.murata.com/products/productdetail?partno=GRM155R61H104KE14%23"
			(at 0 0 0)
			(layer "F.Fab")
			(hide yes)
			(effects
				(font
					(size 1.27 1.27)
					(thickness 0.15)
				)
			)
		)
		(property "Description" "SMD Multilayer Ceramic Capacitor, 0.1 µF, 50 V, 0402 [1005 Metric], ± 10%, X5R, GRM Series"
			(at 0 0 0)
			(layer "F.Fab")
			(hide yes)
			(effects
				(font
					(size 1.27 1.27)
					(thickness 0.15)
				)
			)
		)
		(property "Manufacturer" "Murata"
			(at 0 0 180)
			(unlocked yes)
			(layer "F.Fab")
			(hide yes)
			(effects
				(font
					(size 1 1)
					(thickness 0.15)
				)
			)
		)
		(property "MPN" "GRM155R61H104KE14D"
			(at 0 0 180)
			(unlocked yes)
			(layer "F.Fab")
			(hide yes)
			(effects
				(font
					(size 1 1)
					(thickness 0.15)
				)
			)
		)
		(property "Val" "100n"
			(at 0 0 180)
			(unlocked yes)
			(layer "F.Fab")
			(hide yes)
			(effects
				(font
					(size 1 1)
					(thickness 0.15)
				)
			)
		)
		(property "License" "Apache-2.0"
			(at 0 0 180)
			(unlocked yes)
			(layer "F.Fab")
			(hide yes)
			(effects
				(font
					(size 1 1)
					(thickness 0.15)
				)
			)
		)
		(property "Author" "Antmicro"
			(at 0 0 180)
			(unlocked yes)
			(layer "F.Fab")
			(hide yes)
			(effects
				(font
					(size 1 1)
					(thickness 0.15)
				)
			)
		)
		(property "Voltage" "50V"
			(at 0 0 180)
			(unlocked yes)
			(layer "F.Fab")
			(hide yes)
			(effects
				(font
					(size 1 1)
					(thickness 0.15)
				)
			)
		)
		(property "Dielectric" "X5R"
			(at 0 0 180)
			(unlocked yes)
			(layer "F.Fab")
			(hide yes)
			(effects
				(font
					(size 1 1)
					(thickness 0.15)
				)
			)
		)
		(sheetname "/SoM_IO/")
		(sheetfile "som_io.kicad_sch")
		(attr smd)
		(fp_poly
			(pts
				(xy -0.925 -0.47) (xy -0.925 0.47) (xy 0.925 0.47) (xy 0.925 -0.47)
			)
			(stroke
				(width 0.05)
				(type default)
			)
			(fill no)
			(layer "F.CrtYd")
		)
		(fp_line
			(start 0.504 0.248)
			(end -0.494 0.248)
			(stroke
				(width 0.15)
				(type solid)
			)
			(layer "F.Fab")
		)
		(fp_line
			(start 0.504 -0.25)
			(end 0.504 0.248)
			(stroke
				(width 0.15)
				(type solid)
			)
			(layer "F.Fab")
		)
		(fp_line
			(start -0.494 0.248)
			(end -0.494 -0.25)
			(stroke
				(width 0.15)
				(type solid)
			)
			(layer "F.Fab")
		)
		(fp_line
			(start -0.494 -0.25)
			(end 0.504 -0.25)
			(stroke
				(width 0.15)
				(type solid)
			)
			(layer "F.Fab")
		)
		(fp_text user "License: Apache-2.0"
			(at -0.939 5.799 0)
			(layer "F.Fab")
			(effects
				(font
					(size 0.7 0.7)
					(thickness 0.15)
				)
				(justify right top)
			)
		)
		(fp_text user "${REFERENCE}"
			(at -0.939 4.599 0)
			(layer "F.Fab")
			(effects
				(font
					(size 0.7 0.7)
					(thickness 0.15)
				)
				(justify right top)
			)
		)
		(fp_text user "Author: Antmicro"
			(at -0.939 3.399 0)
			(layer "F.Fab")
			(effects
				(font
					(size 0.7 0.7)
					(thickness 0.15)
				)
				(justify right top)
			)
		)
		(pad "1" smd roundrect
			(at -0.48 0 180)
			(size 0.59 0.64)
			(layers "F.Cu" "F.Mask" "F.Paste")
			(roundrect_rratio 0.25)
			(net 1 "GND")
			(pintype "passive")
		)
		(pad "2" smd roundrect
			(at 0.48 0 180)
			(size 0.59 0.64)
			(layers "F.Cu" "F.Mask" "F.Paste")
			(roundrect_rratio 0.25)
			(net 2 "+3V3")
			(pintype "passive")
		)
	)
)
